(kicad_pcb
	(version 20260206)
	(generator "pcbnew")
	(generator_version "10.0")
	(general
		(thickness 1.6)
		(legacy_teardrops no)
	)
	(paper "A4")
	(title_block
		(title "Wiwynn_Tioga_Pass_MB.brd")
		(comment 1 "Tioga Pass / footprints 1797-1803 of 4770")
	)
	(layers
		(0 "F.Cu" signal "TOP")
		(4 "In1.Cu" signal "L2GND")
		(6 "In2.Cu" signal "L3")
		(8 "In3.Cu" signal "L4GND")
		(10 "In4.Cu" signal "L5")
		(12 "In5.Cu" signal "L6GND")
		(14 "In6.Cu" signal "L7VCC")
		(16 "In7.Cu" signal "L8VCC")
		(18 "In8.Cu" signal "L9GND")
		(20 "In9.Cu" signal "L10")
		(22 "In10.Cu" signal "L11GND")
		(24 "In11.Cu" signal "L12")
		(26 "In12.Cu" signal "L13GND")
		(2 "B.Cu" signal "BOTTOM")
		(9 "F.Adhes" user "F.Adhesive")
		(11 "B.Adhes" user "B.Adhesive")
		(13 "F.Paste" user "Package Geometry/Pastemask Top")
		(15 "B.Paste" user "Package Geometry/Pastemask Bottom")
		(5 "F.SilkS" user "Ref Des/Silkscreen Top")
		(7 "B.SilkS" user "Ref Des/Silkscreen Bottom")
		(1 "F.Mask" user "Board Geometry/Soldermask Top")
		(3 "B.Mask" user "Board Geometry/Soldermask Bottom")
		(17 "Dwgs.User" user "User.Drawings")
		(19 "Cmts.User" user "User.Comments")
		(21 "Eco1.User" user "User.Eco1")
		(23 "Eco2.User" user "User.Eco2")
		(25 "Edge.Cuts" user "Board Geometry/Outline")
		(27 "Margin" user)
		(31 "F.CrtYd" user "Package Geometry/Place Bound Top")
		(29 "B.CrtYd" user "Package Geometry/Place Bound Bottom")
		(35 "F.Fab" user "Ref Des/Assembly Top")
		(33 "B.Fab" user "Ref Des/Assembly Bottom")
	)
	(footprint ""
		(layer "F.Cu")
		(at 341.049864 1.898904 180)
		(property "Reference" "L7G2"
			(at 3.378708 -4.251706 180)
			(unlocked yes)
			(layer "F.SilkS")
			(effects
				(font
					(size 0.4064 0.254)
					(thickness 0.1524)
				)
			)
		)
		(property "Value" ""
			(at 0 0 180)
			(layer "F.Fab")
			(effects
				(font
					(size 1.27 1.27)
				)
			)
		)
		(duplicate_pad_numbers_are_jumpers no)
		(fp_line
			(start 8.3693 3.199892)
			(end -1.1303 3.199892)
			(stroke
				(width 0.1524)
				(type default)
			)
			(layer "F.SilkS")
		)
		(fp_line
			(start 8.3693 1.6637)
			(end 8.3693 3.199892)
			(stroke
				(width 0.1524)
				(type default)
			)
			(layer "F.SilkS")
		)
		(fp_line
			(start 8.3693 -3.199892)
			(end 8.3693 -1.6637)
			(stroke
				(width 0.1524)
				(type default)
			)
			(layer "F.SilkS")
		)
		(fp_line
			(start -1.1303 3.199892)
			(end -1.1303 1.6637)
			(stroke
				(width 0.1524)
				(type default)
			)
			(layer "F.SilkS")
		)
		(fp_line
			(start -1.1303 -1.6637)
			(end -1.1303 -3.199892)
			(stroke
				(width 0.1524)
				(type default)
			)
			(layer "F.SilkS")
		)
		(fp_line
			(start -1.1303 -3.199892)
			(end 8.3693 -3.199892)
			(stroke
				(width 0.1524)
				(type default)
			)
			(layer "F.SilkS")
		)
		(fp_rect
			(start -1.1303 3.199892)
			(end 8.3693 -3.199892)
			(stroke
				(width 0)
				(type default)
			)
			(fill no)
			(layer "F.CrtYd")
		)
		(fp_line
			(start 8.3693 3.199892)
			(end -1.1303 3.199892)
			(stroke
				(width 0.1)
				(type default)
			)
			(layer "F.Fab")
		)
		(fp_line
			(start 8.3693 -3.199892)
			(end 8.3693 3.199892)
			(stroke
				(width 0.1)
				(type default)
			)
			(layer "F.Fab")
		)
		(fp_line
			(start -1.1303 3.199892)
			(end -1.1303 -3.199892)
			(stroke
				(width 0.1)
				(type default)
			)
			(layer "F.Fab")
		)
		(fp_line
			(start -1.1303 -3.199892)
			(end 8.3693 -3.199892)
			(stroke
				(width 0.1)
				(type default)
			)
			(layer "F.Fab")
		)
		(pad "1" smd rect
			(at 0 0 180)
			(size 3.683 2.667)
			(layers "F.Cu" "F.Mask" "F.Paste")
			(net "VR_PVDDQ_ABC_PH2_SW")
		)
		(pad "2" smd rect
			(at 7.239 0 180)
			(size 3.683 2.667)
			(layers "F.Cu" "F.Mask" "F.Paste")
			(net "PVDDQ_ABC")
		)
	)
	(footprint ""
		(layer "F.Cu")
		(at 6.843522 -13.302996 -90)
		(property "Reference" "RT22"
			(at 0 0 270)
			(layer "F.SilkS")
			(hide yes)
			(effects
				(font
					(size 1.27 1.27)
				)
			)
		)
		(property "Value" "*"
			(at -0.0254 -2.6289 270)
			(unlocked yes)
			(layer "F.Fab")
			(hide yes)
			(effects
				(font
					(size 1.27 1.016)
					(thickness 0.1524)
				)
			)
		)
		(property "Device Type" "1R3F-GP_RCL_GP-1R3F-GP,64.1R00A"
			(at -0.0254 -4.1529 270)
			(unlocked yes)
			(layer "F.Fab")
			(hide yes)
			(effects
				(font
					(size 1.27 1.016)
					(thickness 0.1524)
				)
			)
		)
		(duplicate_pad_numbers_are_jumpers no)
		(fp_line
			(start -0.4826 0)
			(end -0.2032 0)
			(stroke
				(width 0.2032)
				(type default)
			)
			(layer "F.SilkS")
		)
		(fp_line
			(start 0.2032 0)
			(end 0.4826 0)
			(stroke
				(width 0.2032)
				(type default)
			)
			(layer "F.SilkS")
		)
		(fp_rect
			(start -0.5842 1.3335)
			(end 0.5842 -1.3335)
			(stroke
				(width 0)
				(type default)
			)
			(fill no)
			(layer "F.CrtYd")
		)
		(fp_rect
			(start -0.5842 1.3335)
			(end 0.5842 -1.3335)
			(stroke
				(width 0)
				(type default)
			)
			(fill no)
			(layer "F.Fab")
		)
		(pad "1" smd custom
			(at 0 -0.762 270)
			(size 0.2159 0.2159)
			(layers "F.Cu" "F.Mask" "F.Paste")
			(net "VR_PVDDQ_GHJ_PH2_SW_RC")
			(options
				(clearance outline)
				(anchor circle)
			)
			(primitives
				(gr_poly
					(pts
						(arc
							(start -0.3302 -0.4318)
							(mid -0.402042 -0.402042)
							(end -0.4318 -0.3302)
						)
						(arc
							(start -0.4318 0.3302)
							(mid -0.402042 0.402042)
							(end -0.3302 0.4318)
						)
						(arc
							(start 0.3302 0.4318)
							(mid 0.402042 0.402042)
							(end 0.4318 0.3302)
						)
						(arc
							(start 0.4318 -0.3302)
							(mid 0.402042 -0.402042)
							(end 0.3302 -0.4318)
						)
					)
					(width 0)
					(fill yes)
				)
			)
		)
		(pad "2" smd custom
			(at 0 0.762 270)
			(size 0.2159 0.2159)
			(layers "F.Cu" "F.Mask" "F.Paste")
			(net "GND")
			(options
				(clearance outline)
				(anchor circle)
			)
			(primitives
				(gr_poly
					(pts
						(arc
							(start -0.3302 -0.4318)
							(mid -0.402042 -0.402042)
							(end -0.4318 -0.3302)
						)
						(arc
							(start -0.4318 0.3302)
							(mid -0.402042 0.402042)
							(end -0.3302 0.4318)
						)
						(arc
							(start 0.3302 0.4318)
							(mid 0.402042 0.402042)
							(end 0.4318 0.3302)
						)
						(arc
							(start 0.4318 -0.3302)
							(mid 0.402042 -0.402042)
							(end 0.3302 -0.4318)
						)
					)
					(width 0)
					(fill yes)
				)
			)
		)
	)
	(footprint ""
		(layer "F.Cu")
		(at 190.754 -94.107 -90)
		(property "Reference" "C4C12"
			(at 1.905 7.84733 90)
			(unlocked yes)
			(layer "F.SilkS")
			(effects
				(font
					(size 0.7874 0.5842)
					(thickness 0.1524)
				)
				(justify left)
			)
		)
		(property "Value" ""
			(at 0 0 270)
			(layer "F.Fab")
			(effects
				(font
					(size 1.27 1.27)
				)
			)
		)
		(duplicate_pad_numbers_are_jumpers no)
		(fp_line
			(start -3.400044 6.067044)
			(end -0.9017 6.067044)
			(stroke
				(width 0.1524)
				(type default)
			)
			(layer "F.SilkS")
		)
		(fp_line
			(start 0.9017 6.067044)
			(end 3.400044 6.067044)
			(stroke
				(width 0.1524)
				(type default)
			)
			(layer "F.SilkS")
		)
		(fp_line
			(start 3.400044 6.067044)
			(end 3.400044 0.028956)
			(stroke
				(width 0.1524)
				(type default)
			)
			(layer "F.SilkS")
		)
		(fp_line
			(start -0.9017 1.587754)
			(end -0.7239 1.587754)
			(stroke
				(width 0.1524)
				(type default)
			)
			(layer "F.SilkS")
		)
		(fp_line
			(start 0.7239 1.587754)
			(end 0.9017 1.587754)
			(stroke
				(width 0.1524)
				(type default)
			)
			(layer "F.SilkS")
		)
		(fp_line
			(start 0.9017 1.587754)
			(end 0.9017 -1.714246)
			(stroke
				(width 0.1524)
				(type default)
			)
			(layer "F.SilkS")
		)
		(fp_line
			(start -3.400044 0.028956)
			(end -3.400044 6.067044)
			(stroke
				(width 0.1524)
				(type default)
			)
			(layer "F.SilkS")
		)
		(fp_line
			(start 3.400044 0.028956)
			(end 2.638044 -0.733044)
			(stroke
				(width 0.1524)
				(type default)
			)
			(layer "F.SilkS")
		)
		(fp_line
			(start -2.638044 -0.733044)
			(end -3.400044 0.028956)
			(stroke
				(width 0.1524)
				(type default)
			)
			(layer "F.SilkS")
		)
		(fp_line
			(start -0.9017 -0.733044)
			(end -2.638044 -0.733044)
			(stroke
				(width 0.1524)
				(type default)
			)
			(layer "F.SilkS")
		)
		(fp_line
			(start 2.638044 -0.733044)
			(end 0.9017 -0.733044)
			(stroke
				(width 0.1524)
				(type default)
			)
			(layer "F.SilkS")
		)
		(fp_line
			(start -0.9017 -1.714246)
			(end -0.9017 1.587754)
			(stroke
				(width 0.1524)
				(type default)
			)
			(layer "F.SilkS")
		)
		(fp_line
			(start -0.7239 -1.714246)
			(end -0.9017 -1.714246)
			(stroke
				(width 0.1524)
				(type default)
			)
			(layer "F.SilkS")
		)
		(fp_line
			(start 0.9017 -1.714246)
			(end 0.7239 -1.714246)
			(stroke
				(width 0.1524)
				(type default)
			)
			(layer "F.SilkS")
		)
		(fp_poly
			(pts
				(xy -3.400044 6.067044) (xy 3.400044 6.067044) (xy 3.400044 0.028956) (xy 2.638044 -0.733044) (xy -2.638044 -0.733044)
				(xy -3.400044 0.028956)
			)
			(stroke
				(width 0)
				(type default)
			)
			(fill no)
			(layer "F.CrtYd")
		)
		(fp_line
			(start -3.400044 6.067044)
			(end 3.400044 6.067044)
			(stroke
				(width 0.1)
				(type default)
			)
			(layer "F.Fab")
		)
		(fp_line
			(start 3.400044 6.067044)
			(end 3.400044 0.028956)
			(stroke
				(width 0.1)
				(type default)
			)
			(layer "F.Fab")
		)
		(fp_line
			(start -3.400044 0.028956)
			(end -3.400044 6.067044)
			(stroke
				(width 0.1)
				(type default)
			)
			(layer "F.Fab")
		)
		(fp_line
			(start 3.400044 0.028956)
			(end 2.638044 -0.733044)
			(stroke
				(width 0.1)
				(type default)
			)
			(layer "F.Fab")
		)
		(fp_line
			(start -2.638044 -0.733044)
			(end -3.400044 0.028956)
			(stroke
				(width 0.1)
				(type default)
			)
			(layer "F.Fab")
		)
		(fp_line
			(start 2.638044 -0.733044)
			(end -2.638044 -0.733044)
			(stroke
				(width 0.1)
				(type default)
			)
			(layer "F.Fab")
		)
		(fp_circle
			(center 0 2.667)
			(end 0 -0.733044)
			(stroke
				(width 0.1)
				(type default)
			)
			(fill no)
			(layer "F.Fab")
		)
		(pad "1" smd rect
			(at 0 0 270)
			(size 0.7874 3.429)
			(layers "F.Cu" "F.Mask" "F.Paste")
			(net "VR_FET_SW_P12V_STBY_PVCCIN_CPU0")
		)
		(pad "2" smd rect
			(at 0 5.334 270)
			(size 0.7874 3.429)
			(layers "F.Cu" "F.Mask" "F.Paste")
			(net "GND")
		)
	)
	(footprint ""
		(layer "F.Cu")
		(at 480.845876 3.820668 90)
		(property "Reference" "C9G13"
			(at 0 0 90)
			(layer "F.SilkS")
			(hide yes)
			(effects
				(font
					(size 1.27 1.27)
				)
			)
		)
		(property "Value" ""
			(at 0 0 90)
			(layer "F.Fab")
			(effects
				(font
					(size 1.27 1.27)
				)
			)
		)
		(duplicate_pad_numbers_are_jumpers no)
		(fp_poly
			(pts
				(xy 0.3048 -0.1016) (xy 0.3048 0.9906) (xy -0.3048 0.9906) (xy -0.3048 -0.1016)
			)
			(stroke
				(width 0)
				(type default)
			)
			(fill no)
			(layer "F.CrtYd")
		)
		(fp_line
			(start 0.3048 -0.1016)
			(end -0.3048 -0.1016)
			(stroke
				(width 0.1)
				(type default)
			)
			(layer "F.Fab")
		)
		(fp_line
			(start -0.3048 -0.1016)
			(end -0.3048 0.9906)
			(stroke
				(width 0.1)
				(type default)
			)
			(layer "F.Fab")
		)
		(fp_line
			(start 0.3048 0.9906)
			(end 0.3048 -0.1016)
			(stroke
				(width 0.1)
				(type default)
			)
			(layer "F.Fab")
		)
		(fp_line
			(start -0.3048 0.9906)
			(end 0.3048 0.9906)
			(stroke
				(width 0.1)
				(type default)
			)
			(layer "F.Fab")
		)
		(pad "1" smd rect
			(at 0 0 90)
			(size 0.508 0.508)
			(layers "F.Cu" "F.Mask" "F.Paste")
			(net "NIC_SET_N_MDI_2_DN")
		)
		(pad "2" smd rect
			(at 0 0.889 90)
			(size 0.508 0.508)
			(layers "F.Cu" "F.Mask" "F.Paste")
			(net "NIC_MDI_MNG_TX_DN")
		)
		(zone
			(layer "F.Cu")
			(hatch none 0.5)
			(connect_pads
				(clearance 0)
			)
			(min_thickness 0.25)
			(keepout
				(tracks allowed)
				(vias not_allowed)
				(pads allowed)
				(copperpour not_allowed)
				(footprints allowed)
			)
			(placement
				(enabled no)
				(sheetname "")
			)
			(fill
				(thermal_gap 0.5)
				(thermal_bridge_width 0.5)
				(island_removal_mode 0)
			)
			(polygon
				(pts
					(xy 481.099876 4.074668) (xy 481.099876 3.566668) (xy 481.480876 3.566668) (xy 481.480876 4.074668)
				)
			)
		)
		(zone
			(layer "F.Cu")
			(hatch none 0.5)
			(connect_pads
				(clearance 0)
			)
			(min_thickness 0.25)
			(keepout
				(tracks not_allowed)
				(vias allowed)
				(pads allowed)
				(copperpour not_allowed)
				(footprints allowed)
			)
			(placement
				(enabled no)
				(sheetname "")
			)
			(fill
				(thermal_gap 0.5)
				(thermal_bridge_width 0.5)
				(island_removal_mode 0)
			)
			(polygon
				(pts
					(xy 481.480876 4.074668) (xy 481.480876 3.566668) (xy 481.099876 3.566668) (xy 481.099876 4.074668)
				)
			)
		)
	)
	(footprint ""
		(layer "F.Cu")
		(at 15.293848 -0.733552 90)
		(property "Reference" "R1G12"
			(at 0 0 90)
			(layer "F.SilkS")
			(hide yes)
			(effects
				(font
					(size 1.27 1.27)
				)
			)
		)
		(property "Value" ""
			(at 0 0 90)
			(layer "F.Fab")
			(effects
				(font
					(size 1.27 1.27)
				)
			)
		)
		(duplicate_pad_numbers_are_jumpers no)
		(fp_rect
			(start 0.2794 -0.1016)
			(end -0.2794 0.9906)
			(stroke
				(width 0)
				(type default)
			)
			(fill no)
			(layer "F.CrtYd")
		)
		(fp_line
			(start 0.2794 -0.1016)
			(end -0.2794 -0.1016)
			(stroke
				(width 0.1)
				(type default)
			)
			(layer "F.Fab")
		)
		(fp_line
			(start -0.2794 -0.1016)
			(end -0.2794 0.9906)
			(stroke
				(width 0.1)
				(type default)
			)
			(layer "F.Fab")
		)
		(fp_line
			(start 0.2794 0.9906)
			(end 0.2794 -0.1016)
			(stroke
				(width 0.1)
				(type default)
			)
			(layer "F.Fab")
		)
		(fp_line
			(start -0.2794 0.9906)
			(end 0.2794 0.9906)
			(stroke
				(width 0.1)
				(type default)
			)
			(layer "F.Fab")
		)
		(pad "1" smd rect
			(at 0 0 90)
			(size 0.508 0.508)
			(layers "F.Cu" "F.Mask" "F.Paste")
			(net "PWRGD_PVDDQ_GHJ_R")
		)
		(pad "2" smd rect
			(at 0 0.889 90)
			(size 0.508 0.508)
			(layers "F.Cu" "F.Mask" "F.Paste")
			(net "PWRGD_PVDDQ_GHJ")
		)
		(zone
			(layer "F.Cu")
			(hatch none 0.5)
			(connect_pads
				(clearance 0)
			)
			(min_thickness 0.25)
			(keepout
				(tracks allowed)
				(vias not_allowed)
				(pads allowed)
				(copperpour not_allowed)
				(footprints allowed)
			)
			(placement
				(enabled no)
				(sheetname "")
			)
			(fill
				(thermal_gap 0.5)
				(thermal_bridge_width 0.5)
				(island_removal_mode 0)
			)
			(polygon
				(pts
					(xy 15.547848 -0.987552) (xy 15.547848 -0.479552) (xy 15.928848 -0.479552) (xy 15.928848 -0.987552)
				)
			)
		)
		(zone
			(layer "F.Cu")
			(hatch none 0.5)
			(connect_pads
				(clearance 0)
			)
			(min_thickness 0.25)
			(keepout
				(tracks not_allowed)
				(vias allowed)
				(pads allowed)
				(copperpour not_allowed)
				(footprints allowed)
			)
			(placement
				(enabled no)
				(sheetname "")
			)
			(fill
				(thermal_gap 0.5)
				(thermal_bridge_width 0.5)
				(island_removal_mode 0)
			)
			(polygon
				(pts
					(xy 15.547848 -0.987552) (xy 15.547848 -0.479552) (xy 15.928848 -0.479552) (xy 15.928848 -0.987552)
				)
			)
		)
	)
	(footprint ""
		(layer "F.Cu")
		(at 411.444694 -132.567172 90)
		(property "Reference" "R8B3"
			(at 0 0 90)
			(layer "F.SilkS")
			(hide yes)
			(effects
				(font
					(size 1.27 1.27)
				)
			)
		)
		(property "Value" ""
			(at 0 0 90)
			(layer "F.Fab")
			(effects
				(font
					(size 1.27 1.27)
				)
			)
		)
		(duplicate_pad_numbers_are_jumpers no)
		(fp_poly
			(pts
				(xy -0.2794 -0.1016) (xy 0.2794 -0.1016) (xy 0.2794 0.9906) (xy -0.2794 0.9906)
			)
			(stroke
				(width 0)
				(type default)
			)
			(fill no)
			(layer "F.CrtYd")
		)
		(fp_line
			(start 0.2794 -0.1016)
			(end -0.2794 -0.1016)
			(stroke
				(width 0.1)
				(type default)
			)
			(layer "F.Fab")
		)
		(fp_line
			(start -0.2794 -0.1016)
			(end -0.2794 0.9906)
			(stroke
				(width 0.1)
				(type default)
			)
			(layer "F.Fab")
		)
		(fp_line
			(start 0.2794 0.9906)
			(end 0.2794 -0.1016)
			(stroke
				(width 0.1)
				(type default)
			)
			(layer "F.Fab")
		)
		(fp_line
			(start -0.2794 0.9906)
			(end 0.2794 0.9906)
			(stroke
				(width 0.1)
				(type default)
			)
			(layer "F.Fab")
		)
		(pad "1" smd rect
			(at 0 0 90)
			(size 0.508 0.508)
			(layers "F.Cu" "F.Mask" "F.Paste")
			(net "PVPP_ABC")
		)
		(pad "2" smd rect
			(at 0 0.889 90)
			(size 0.508 0.508)
			(layers "F.Cu" "F.Mask" "F.Paste")
			(net "FM_MODPRST_HFI0_CPU0_LVT2_N")
		)
		(zone
			(layer "F.Cu")
			(hatch none 0.5)
			(connect_pads
				(clearance 0)
			)
			(min_thickness 0.25)
			(keepout
				(tracks allowed)
				(vias not_allowed)
				(pads allowed)
				(copperpour not_allowed)
				(footprints allowed)
			)
			(placement
				(enabled no)
				(sheetname "")
			)
			(fill
				(thermal_gap 0.5)
				(thermal_bridge_width 0.5)
				(island_removal_mode 0)
			)
			(polygon
				(pts
					(xy 411.698694 -132.313172) (xy 411.698694 -132.821172) (xy 412.079694 -132.821172) (xy 412.079694 -132.313172)
				)
			)
		)
		(zone
			(layer "F.Cu")
			(hatch none 0.5)
			(connect_pads
				(clearance 0)
			)
			(min_thickness 0.25)
			(keepout
				(tracks not_allowed)
				(vias allowed)
				(pads allowed)
				(copperpour not_allowed)
				(footprints allowed)
			)
			(placement
				(enabled no)
				(sheetname "")
			)
			(fill
				(thermal_gap 0.5)
				(thermal_bridge_width 0.5)
				(island_removal_mode 0)
			)
			(polygon
				(pts
					(xy 412.079694 -132.313172) (xy 412.079694 -132.821172) (xy 411.698694 -132.821172) (xy 411.698694 -132.313172)
				)
			)
		)
	)
	(footprint ""
		(layer "F.Cu")
		(at 405.1935 -116.967 90)
		(property "Reference" "C8B13"
			(at 0 0 90)
			(layer "F.SilkS")
			(hide yes)
			(effects
				(font
					(size 1.27 1.27)
				)
			)
		)
		(property "Value" ""
			(at 0 0 90)
			(layer "F.Fab")
			(effects
				(font
					(size 1.27 1.27)
				)
			)
		)
		(duplicate_pad_numbers_are_jumpers no)
		(fp_poly
			(pts
				(xy -0.4953 -0.2032) (xy 0.4953 -0.2032) (xy 0.4953 1.6002) (xy -0.4953 1.6002)
			)
			(stroke
				(width 0)
				(type default)
			)
			(fill no)
			(layer "F.CrtYd")
		)
		(fp_line
			(start 0.4953 -0.2032)
			(end 0.4953 1.6002)
			(stroke
				(width 0.1)
				(type default)
			)
			(layer "F.Fab")
		)
		(fp_line
			(start -0.4953 -0.2032)
			(end 0.4953 -0.2032)
			(stroke
				(width 0.1)
				(type default)
			)
			(layer "F.Fab")
		)
		(fp_line
			(start 0.4953 1.6002)
			(end -0.4953 1.6002)
			(stroke
				(width 0.1)
				(type default)
			)
			(layer "F.Fab")
		)
		(fp_line
			(start -0.4953 1.6002)
			(end -0.4953 -0.2032)
			(stroke
				(width 0.1)
				(type default)
			)
			(layer "F.Fab")
		)
		(pad "1" smd rect
			(at 0 0 90)
			(size 0.762 0.889)
			(layers "F.Cu" "F.Mask" "F.Paste")
			(net "P1V05_PCH_STBY")
		)
		(pad "2" smd rect
			(at 0 1.397 90)
			(size 0.762 0.889)
			(layers "F.Cu" "F.Mask" "F.Paste")
			(net "GND")
		)
		(zone
			(layer "F.Cu")
			(hatch none 0.5)
			(connect_pads
				(clearance 0)
			)
			(min_thickness 0.25)
			(keepout
				(tracks not_allowed)
				(vias allowed)
				(pads allowed)
				(copperpour not_allowed)
				(footprints allowed)
			)
			(placement
				(enabled no)
				(sheetname "")
			)
			(fill
				(thermal_gap 0.5)
				(thermal_bridge_width 0.5)
				(island_removal_mode 0)
			)
			(polygon
				(pts
					(xy 405.638 -116.586) (xy 405.638 -117.348) (xy 406.146 -117.348) (xy 406.146 -116.586)
				)
			)
		)
	)
)
